(kicad_pcb
	(version 20260206)
	(generator "pcbnew")
	(generator_version "10.0")
	(general
		(thickness 1.6)
		(legacy_teardrops no)
	)
	(paper "A4")
	(title_block
		(title "12092022_DA0F0TMDCD0_F0T_Management_Board_D_brd_V3_OCP.brd")
		(comment 1 "Grand Teton / footprints 920-926 of 1440")
	)
	(layers
		(0 "F.Cu" signal "TOP")
		(4 "In1.Cu" signal "GND")
		(6 "In2.Cu" signal "IN1")
		(8 "In3.Cu" signal "GND1")
		(10 "In4.Cu" signal "IN2")
		(12 "In5.Cu" signal "VCC")
		(14 "In6.Cu" signal "VCC1")
		(16 "In7.Cu" signal "IN3")
		(18 "In8.Cu" signal "GND2")
		(20 "In9.Cu" signal "IN4")
		(22 "In10.Cu" signal "GND3")
		(2 "B.Cu" signal "BOTTOM")
		(9 "F.Adhes" user "F.Adhesive")
		(11 "B.Adhes" user "B.Adhesive")
		(13 "F.Paste" user "Package Geometry/Pastemask Top")
		(15 "B.Paste" user "Package Geometry/Pastemask Bottom")
		(5 "F.SilkS" user "Ref Des/Silkscreen Top")
		(7 "B.SilkS" user "Ref Des/Silkscreen Bottom")
		(1 "F.Mask" user "Board Geometry/Soldermask Top")
		(3 "B.Mask" user "Board Geometry/Soldermask Bottom")
		(17 "Dwgs.User" user "User.Drawings")
		(19 "Cmts.User" user "User.Comments")
		(21 "Eco1.User" user "User.Eco1")
		(23 "Eco2.User" user "User.Eco2")
		(25 "Edge.Cuts" user "Board Geometry/Outline")
		(27 "Margin" user)
		(31 "F.CrtYd" user "Package Geometry/Place Bound Top")
		(29 "B.CrtYd" user "Package Geometry/Place Bound Bottom")
		(35 "F.Fab" user "Ref Des/Assembly Top")
		(33 "B.Fab" user "Ref Des/Assembly Bottom")
	)
	(footprint ""
		(layer "B.Cu")
		(at 73.783698 -37.271706 -90)
		(property "Reference" "C58"
			(at 0 0 90)
			(layer "B.SilkS")
			(hide yes)
			(effects
				(font
					(size 1.27 1.27)
				)
				(justify mirror)
			)
		)
		(property "Value" ""
			(at 0 0 90)
			(layer "B.Fab")
			(effects
				(font
					(size 1.27 1.27)
				)
				(justify mirror)
			)
		)
		(duplicate_pad_numbers_are_jumpers no)
		(fp_line
			(start -0.7874 0.4064)
			(end 0.7874 0.4064)
			(stroke
				(width 0.1524)
				(type default)
			)
			(layer "B.SilkS")
		)
		(fp_line
			(start 0.7874 0.4064)
			(end 0.7874 -0.4064)
			(stroke
				(width 0.1524)
				(type default)
			)
			(layer "B.SilkS")
		)
		(fp_line
			(start -0.7874 -0.4064)
			(end -0.7874 0.4064)
			(stroke
				(width 0.1524)
				(type default)
			)
			(layer "B.SilkS")
		)
		(fp_line
			(start 0.7874 -0.4064)
			(end -0.7874 -0.4064)
			(stroke
				(width 0.1524)
				(type default)
			)
			(layer "B.SilkS")
		)
		(fp_line
			(start -0.67945 0.3048)
			(end -0.120396 0.3048)
			(stroke
				(width 0.1)
				(type default)
			)
			(layer "B.Fab")
		)
		(fp_line
			(start -0.120396 0.3048)
			(end -0.120396 0.2794)
			(stroke
				(width 0.1)
				(type default)
			)
			(layer "B.Fab")
		)
		(fp_line
			(start 0.12065 0.3048)
			(end 0.67945 0.3048)
			(stroke
				(width 0.1)
				(type default)
			)
			(layer "B.Fab")
		)
		(fp_line
			(start 0.67945 0.3048)
			(end 0.67945 -0.305054)
			(stroke
				(width 0.1)
				(type default)
			)
			(layer "B.Fab")
		)
		(fp_line
			(start -0.120396 0.2794)
			(end 0.12065 0.2794)
			(stroke
				(width 0.1)
				(type default)
			)
			(layer "B.Fab")
		)
		(fp_line
			(start 0.12065 0.2794)
			(end 0.12065 0.3048)
			(stroke
				(width 0.1)
				(type default)
			)
			(layer "B.Fab")
		)
		(fp_line
			(start -0.12065 -0.2794)
			(end -0.12065 -0.3048)
			(stroke
				(width 0.1)
				(type default)
			)
			(layer "B.Fab")
		)
		(fp_line
			(start 0.12065 -0.2794)
			(end -0.12065 -0.2794)
			(stroke
				(width 0.1)
				(type default)
			)
			(layer "B.Fab")
		)
		(fp_line
			(start -0.67945 -0.3048)
			(end -0.67945 0.3048)
			(stroke
				(width 0.1)
				(type default)
			)
			(layer "B.Fab")
		)
		(fp_line
			(start -0.12065 -0.3048)
			(end -0.67945 -0.3048)
			(stroke
				(width 0.1)
				(type default)
			)
			(layer "B.Fab")
		)
		(fp_line
			(start 0.12065 -0.305054)
			(end 0.12065 -0.2794)
			(stroke
				(width 0.1)
				(type default)
			)
			(layer "B.Fab")
		)
		(fp_line
			(start 0.67945 -0.305054)
			(end 0.12065 -0.305054)
			(stroke
				(width 0.1)
				(type default)
			)
			(layer "B.Fab")
		)
		(pad "1" smd circle
			(at 0.40005 0 90)
			(size 0 0)
			(layers "B.Cu" "B.Mask" "B.Paste")
			(net "P1V2_AUX")
		)
		(pad "2" smd circle
			(at -0.40005 0 90)
			(size 0 0)
			(layers "B.Cu" "B.Mask" "B.Paste")
			(net "GND")
		)
	)
	(footprint ""
		(layer "B.Cu")
		(at 66.4972 -72.4662 -90)
		(property "Reference" "R309"
			(at 0 0 90)
			(layer "B.SilkS")
			(hide yes)
			(effects
				(font
					(size 1.27 1.27)
				)
				(justify mirror)
			)
		)
		(property "Value" ""
			(at 0 0 90)
			(layer "B.Fab")
			(effects
				(font
					(size 1.27 1.27)
				)
				(justify mirror)
			)
		)
		(duplicate_pad_numbers_are_jumpers no)
		(fp_line
			(start -0.7874 0.4064)
			(end 0.7874 0.4064)
			(stroke
				(width 0.1524)
				(type default)
			)
			(layer "B.SilkS")
		)
		(fp_line
			(start 0.7874 0.4064)
			(end 0.7874 -0.4064)
			(stroke
				(width 0.1524)
				(type default)
			)
			(layer "B.SilkS")
		)
		(fp_line
			(start -0.7874 -0.4064)
			(end -0.7874 0.4064)
			(stroke
				(width 0.1524)
				(type default)
			)
			(layer "B.SilkS")
		)
		(fp_line
			(start 0.7874 -0.4064)
			(end -0.7874 -0.4064)
			(stroke
				(width 0.1524)
				(type default)
			)
			(layer "B.SilkS")
		)
		(fp_line
			(start -0.67945 0.3048)
			(end -0.120396 0.3048)
			(stroke
				(width 0.1)
				(type default)
			)
			(layer "B.Fab")
		)
		(fp_line
			(start -0.120396 0.3048)
			(end -0.120396 0.2794)
			(stroke
				(width 0.1)
				(type default)
			)
			(layer "B.Fab")
		)
		(fp_line
			(start 0.12065 0.3048)
			(end 0.67945 0.3048)
			(stroke
				(width 0.1)
				(type default)
			)
			(layer "B.Fab")
		)
		(fp_line
			(start 0.67945 0.3048)
			(end 0.67945 -0.305054)
			(stroke
				(width 0.1)
				(type default)
			)
			(layer "B.Fab")
		)
		(fp_line
			(start -0.120396 0.2794)
			(end 0.12065 0.2794)
			(stroke
				(width 0.1)
				(type default)
			)
			(layer "B.Fab")
		)
		(fp_line
			(start 0.12065 0.2794)
			(end 0.12065 0.3048)
			(stroke
				(width 0.1)
				(type default)
			)
			(layer "B.Fab")
		)
		(fp_line
			(start -0.12065 -0.2794)
			(end -0.12065 -0.3048)
			(stroke
				(width 0.1)
				(type default)
			)
			(layer "B.Fab")
		)
		(fp_line
			(start 0.12065 -0.2794)
			(end -0.12065 -0.2794)
			(stroke
				(width 0.1)
				(type default)
			)
			(layer "B.Fab")
		)
		(fp_line
			(start -0.67945 -0.3048)
			(end -0.67945 0.3048)
			(stroke
				(width 0.1)
				(type default)
			)
			(layer "B.Fab")
		)
		(fp_line
			(start -0.12065 -0.3048)
			(end -0.67945 -0.3048)
			(stroke
				(width 0.1)
				(type default)
			)
			(layer "B.Fab")
		)
		(fp_line
			(start 0.12065 -0.305054)
			(end 0.12065 -0.2794)
			(stroke
				(width 0.1)
				(type default)
			)
			(layer "B.Fab")
		)
		(fp_line
			(start 0.67945 -0.305054)
			(end 0.12065 -0.305054)
			(stroke
				(width 0.1)
				(type default)
			)
			(layer "B.Fab")
		)
		(pad "1" smd circle
			(at 0.40005 0 90)
			(size 0 0)
			(layers "B.Cu" "B.Mask" "B.Paste")
			(net "SPI_BMC_TPM_MOSI_R1")
		)
		(pad "2" smd circle
			(at -0.40005 0 90)
			(size 0 0)
			(layers "B.Cu" "B.Mask" "B.Paste")
			(net "SPI_BMC_TPM_MOSI")
		)
	)
	(footprint ""
		(layer "B.Cu")
		(at 51.2445 -93.2815 180)
		(property "Reference" "R632"
			(at 0 0 0)
			(layer "B.SilkS")
			(hide yes)
			(effects
				(font
					(size 1.27 1.27)
				)
				(justify mirror)
			)
		)
		(property "Value" ""
			(at 0 0 0)
			(layer "B.Fab")
			(effects
				(font
					(size 1.27 1.27)
				)
				(justify mirror)
			)
		)
		(duplicate_pad_numbers_are_jumpers no)
		(fp_line
			(start 0.7874 0.4064)
			(end 0.7874 -0.4064)
			(stroke
				(width 0.1524)
				(type default)
			)
			(layer "B.SilkS")
		)
		(fp_line
			(start 0.7874 -0.4064)
			(end -0.7874 -0.4064)
			(stroke
				(width 0.1524)
				(type default)
			)
			(layer "B.SilkS")
		)
		(fp_line
			(start -0.7874 0.4064)
			(end 0.7874 0.4064)
			(stroke
				(width 0.1524)
				(type default)
			)
			(layer "B.SilkS")
		)
		(fp_line
			(start -0.7874 -0.4064)
			(end -0.7874 0.4064)
			(stroke
				(width 0.1524)
				(type default)
			)
			(layer "B.SilkS")
		)
		(fp_line
			(start 0.67945 0.3048)
			(end 0.67945 -0.305054)
			(stroke
				(width 0.1)
				(type default)
			)
			(layer "B.Fab")
		)
		(fp_line
			(start 0.67945 -0.305054)
			(end 0.12065 -0.305054)
			(stroke
				(width 0.1)
				(type default)
			)
			(layer "B.Fab")
		)
		(fp_line
			(start 0.12065 0.3048)
			(end 0.67945 0.3048)
			(stroke
				(width 0.1)
				(type default)
			)
			(layer "B.Fab")
		)
		(fp_line
			(start 0.12065 0.2794)
			(end 0.12065 0.3048)
			(stroke
				(width 0.1)
				(type default)
			)
			(layer "B.Fab")
		)
		(fp_line
			(start 0.12065 -0.2794)
			(end -0.12065 -0.2794)
			(stroke
				(width 0.1)
				(type default)
			)
			(layer "B.Fab")
		)
		(fp_line
			(start 0.12065 -0.305054)
			(end 0.12065 -0.2794)
			(stroke
				(width 0.1)
				(type default)
			)
			(layer "B.Fab")
		)
		(fp_line
			(start -0.120396 0.3048)
			(end -0.120396 0.2794)
			(stroke
				(width 0.1)
				(type default)
			)
			(layer "B.Fab")
		)
		(fp_line
			(start -0.120396 0.2794)
			(end 0.12065 0.2794)
			(stroke
				(width 0.1)
				(type default)
			)
			(layer "B.Fab")
		)
		(fp_line
			(start -0.12065 -0.2794)
			(end -0.12065 -0.3048)
			(stroke
				(width 0.1)
				(type default)
			)
			(layer "B.Fab")
		)
		(fp_line
			(start -0.12065 -0.3048)
			(end -0.67945 -0.3048)
			(stroke
				(width 0.1)
				(type default)
			)
			(layer "B.Fab")
		)
		(fp_line
			(start -0.67945 0.3048)
			(end -0.120396 0.3048)
			(stroke
				(width 0.1)
				(type default)
			)
			(layer "B.Fab")
		)
		(fp_line
			(start -0.67945 -0.3048)
			(end -0.67945 0.3048)
			(stroke
				(width 0.1)
				(type default)
			)
			(layer "B.Fab")
		)
		(pad "1" smd circle
			(at 0.40005 0)
			(size 0 0)
			(layers "B.Cu" "B.Mask" "B.Paste")
			(net "SMB_DEBUG_AUX_LVC3_USB_SCL")
		)
		(pad "2" smd circle
			(at -0.40005 0)
			(size 0 0)
			(layers "B.Cu" "B.Mask" "B.Paste")
			(net "SMB_DEBUG_AUX_LVC3_USB_R3_SCL")
		)
	)
	(footprint ""
		(layer "B.Cu")
		(at 59.563 -34.7218 90)
		(property "Reference" "R142"
			(at 0 0 90)
			(layer "B.SilkS")
			(hide yes)
			(effects
				(font
					(size 1.27 1.27)
				)
				(justify mirror)
			)
		)
		(property "Value" ""
			(at 0 0 90)
			(layer "B.Fab")
			(effects
				(font
					(size 1.27 1.27)
				)
				(justify mirror)
			)
		)
		(duplicate_pad_numbers_are_jumpers no)
		(fp_line
			(start 0.7874 -0.4064)
			(end -0.7874 -0.4064)
			(stroke
				(width 0.1524)
				(type default)
			)
			(layer "B.SilkS")
		)
		(fp_line
			(start -0.7874 -0.4064)
			(end -0.7874 0.4064)
			(stroke
				(width 0.1524)
				(type default)
			)
			(layer "B.SilkS")
		)
		(fp_line
			(start 0.7874 0.4064)
			(end 0.7874 -0.4064)
			(stroke
				(width 0.1524)
				(type default)
			)
			(layer "B.SilkS")
		)
		(fp_line
			(start -0.7874 0.4064)
			(end 0.7874 0.4064)
			(stroke
				(width 0.1524)
				(type default)
			)
			(layer "B.SilkS")
		)
		(fp_line
			(start 0.67945 -0.305054)
			(end 0.12065 -0.305054)
			(stroke
				(width 0.1)
				(type default)
			)
			(layer "B.Fab")
		)
		(fp_line
			(start 0.12065 -0.305054)
			(end 0.12065 -0.2794)
			(stroke
				(width 0.1)
				(type default)
			)
			(layer "B.Fab")
		)
		(fp_line
			(start -0.12065 -0.3048)
			(end -0.67945 -0.3048)
			(stroke
				(width 0.1)
				(type default)
			)
			(layer "B.Fab")
		)
		(fp_line
			(start -0.67945 -0.3048)
			(end -0.67945 0.3048)
			(stroke
				(width 0.1)
				(type default)
			)
			(layer "B.Fab")
		)
		(fp_line
			(start 0.12065 -0.2794)
			(end -0.12065 -0.2794)
			(stroke
				(width 0.1)
				(type default)
			)
			(layer "B.Fab")
		)
		(fp_line
			(start -0.12065 -0.2794)
			(end -0.12065 -0.3048)
			(stroke
				(width 0.1)
				(type default)
			)
			(layer "B.Fab")
		)
		(fp_line
			(start 0.12065 0.2794)
			(end 0.12065 0.3048)
			(stroke
				(width 0.1)
				(type default)
			)
			(layer "B.Fab")
		)
		(fp_line
			(start -0.120396 0.2794)
			(end 0.12065 0.2794)
			(stroke
				(width 0.1)
				(type default)
			)
			(layer "B.Fab")
		)
		(fp_line
			(start 0.67945 0.3048)
			(end 0.67945 -0.305054)
			(stroke
				(width 0.1)
				(type default)
			)
			(layer "B.Fab")
		)
		(fp_line
			(start 0.12065 0.3048)
			(end 0.67945 0.3048)
			(stroke
				(width 0.1)
				(type default)
			)
			(layer "B.Fab")
		)
		(fp_line
			(start -0.120396 0.3048)
			(end -0.120396 0.2794)
			(stroke
				(width 0.1)
				(type default)
			)
			(layer "B.Fab")
		)
		(fp_line
			(start -0.67945 0.3048)
			(end -0.120396 0.3048)
			(stroke
				(width 0.1)
				(type default)
			)
			(layer "B.Fab")
		)
		(pad "1" smd circle
			(at 0.40005 0 270)
			(size 0 0)
			(layers "B.Cu" "B.Mask" "B.Paste")
			(net "SMB_BMC_MM6_R_SCL")
		)
		(pad "2" smd circle
			(at -0.40005 0 270)
			(size 0 0)
			(layers "B.Cu" "B.Mask" "B.Paste")
			(net "SMB_BMC_MM6_SCL")
		)
	)
	(footprint ""
		(layer "B.Cu")
		(at 71.68896 -49.849786 -90)
		(property "Reference" "C7"
			(at 0 0 90)
			(layer "B.SilkS")
			(hide yes)
			(effects
				(font
					(size 1.27 1.27)
				)
				(justify mirror)
			)
		)
		(property "Value" ""
			(at 0 0 90)
			(layer "B.Fab")
			(effects
				(font
					(size 1.27 1.27)
				)
				(justify mirror)
			)
		)
		(duplicate_pad_numbers_are_jumpers no)
		(fp_line
			(start -0.7874 0.4064)
			(end 0.7874 0.4064)
			(stroke
				(width 0.1524)
				(type default)
			)
			(layer "B.SilkS")
		)
		(fp_line
			(start 0.7874 0.4064)
			(end 0.7874 -0.4064)
			(stroke
				(width 0.1524)
				(type default)
			)
			(layer "B.SilkS")
		)
		(fp_line
			(start -0.7874 -0.4064)
			(end -0.7874 0.4064)
			(stroke
				(width 0.1524)
				(type default)
			)
			(layer "B.SilkS")
		)
		(fp_line
			(start 0.7874 -0.4064)
			(end -0.7874 -0.4064)
			(stroke
				(width 0.1524)
				(type default)
			)
			(layer "B.SilkS")
		)
		(fp_line
			(start -0.67945 0.3048)
			(end -0.120396 0.3048)
			(stroke
				(width 0.1)
				(type default)
			)
			(layer "B.Fab")
		)
		(fp_line
			(start -0.120396 0.3048)
			(end -0.120396 0.2794)
			(stroke
				(width 0.1)
				(type default)
			)
			(layer "B.Fab")
		)
		(fp_line
			(start 0.12065 0.3048)
			(end 0.67945 0.3048)
			(stroke
				(width 0.1)
				(type default)
			)
			(layer "B.Fab")
		)
		(fp_line
			(start 0.67945 0.3048)
			(end 0.67945 -0.305054)
			(stroke
				(width 0.1)
				(type default)
			)
			(layer "B.Fab")
		)
		(fp_line
			(start -0.120396 0.2794)
			(end 0.12065 0.2794)
			(stroke
				(width 0.1)
				(type default)
			)
			(layer "B.Fab")
		)
		(fp_line
			(start 0.12065 0.2794)
			(end 0.12065 0.3048)
			(stroke
				(width 0.1)
				(type default)
			)
			(layer "B.Fab")
		)
		(fp_line
			(start -0.12065 -0.2794)
			(end -0.12065 -0.3048)
			(stroke
				(width 0.1)
				(type default)
			)
			(layer "B.Fab")
		)
		(fp_line
			(start 0.12065 -0.2794)
			(end -0.12065 -0.2794)
			(stroke
				(width 0.1)
				(type default)
			)
			(layer "B.Fab")
		)
		(fp_line
			(start -0.67945 -0.3048)
			(end -0.67945 0.3048)
			(stroke
				(width 0.1)
				(type default)
			)
			(layer "B.Fab")
		)
		(fp_line
			(start -0.12065 -0.3048)
			(end -0.67945 -0.3048)
			(stroke
				(width 0.1)
				(type default)
			)
			(layer "B.Fab")
		)
		(fp_line
			(start 0.12065 -0.305054)
			(end 0.12065 -0.2794)
			(stroke
				(width 0.1)
				(type default)
			)
			(layer "B.Fab")
		)
		(fp_line
			(start 0.67945 -0.305054)
			(end 0.12065 -0.305054)
			(stroke
				(width 0.1)
				(type default)
			)
			(layer "B.Fab")
		)
		(pad "1" smd circle
			(at 0.40005 0 90)
			(size 0 0)
			(layers "B.Cu" "B.Mask" "B.Paste")
			(net "P1V2_AUX")
		)
		(pad "2" smd circle
			(at -0.40005 0 90)
			(size 0 0)
			(layers "B.Cu" "B.Mask" "B.Paste")
			(net "GND")
		)
	)
	(footprint ""
		(layer "B.Cu")
		(at 42.22115 -38.9636 180)
		(property "Reference" "R242"
			(at 0 0 0)
			(layer "B.SilkS")
			(hide yes)
			(effects
				(font
					(size 1.27 1.27)
				)
				(justify mirror)
			)
		)
		(property "Value" ""
			(at 0 0 0)
			(layer "B.Fab")
			(effects
				(font
					(size 1.27 1.27)
				)
				(justify mirror)
			)
		)
		(duplicate_pad_numbers_are_jumpers no)
		(fp_line
			(start 0.7874 0.4064)
			(end 0.7874 -0.4064)
			(stroke
				(width 0.1524)
				(type default)
			)
			(layer "B.SilkS")
		)
		(fp_line
			(start 0.7874 -0.4064)
			(end -0.7874 -0.4064)
			(stroke
				(width 0.1524)
				(type default)
			)
			(layer "B.SilkS")
		)
		(fp_line
			(start -0.7874 0.4064)
			(end 0.7874 0.4064)
			(stroke
				(width 0.1524)
				(type default)
			)
			(layer "B.SilkS")
		)
		(fp_line
			(start -0.7874 -0.4064)
			(end -0.7874 0.4064)
			(stroke
				(width 0.1524)
				(type default)
			)
			(layer "B.SilkS")
		)
		(fp_line
			(start 0.67945 0.3048)
			(end 0.67945 -0.305054)
			(stroke
				(width 0.1)
				(type default)
			)
			(layer "B.Fab")
		)
		(fp_line
			(start 0.67945 -0.305054)
			(end 0.12065 -0.305054)
			(stroke
				(width 0.1)
				(type default)
			)
			(layer "B.Fab")
		)
		(fp_line
			(start 0.12065 0.3048)
			(end 0.67945 0.3048)
			(stroke
				(width 0.1)
				(type default)
			)
			(layer "B.Fab")
		)
		(fp_line
			(start 0.12065 0.2794)
			(end 0.12065 0.3048)
			(stroke
				(width 0.1)
				(type default)
			)
			(layer "B.Fab")
		)
		(fp_line
			(start 0.12065 -0.2794)
			(end -0.12065 -0.2794)
			(stroke
				(width 0.1)
				(type default)
			)
			(layer "B.Fab")
		)
		(fp_line
			(start 0.12065 -0.305054)
			(end 0.12065 -0.2794)
			(stroke
				(width 0.1)
				(type default)
			)
			(layer "B.Fab")
		)
		(fp_line
			(start -0.120396 0.3048)
			(end -0.120396 0.2794)
			(stroke
				(width 0.1)
				(type default)
			)
			(layer "B.Fab")
		)
		(fp_line
			(start -0.120396 0.2794)
			(end 0.12065 0.2794)
			(stroke
				(width 0.1)
				(type default)
			)
			(layer "B.Fab")
		)
		(fp_line
			(start -0.12065 -0.2794)
			(end -0.12065 -0.3048)
			(stroke
				(width 0.1)
				(type default)
			)
			(layer "B.Fab")
		)
		(fp_line
			(start -0.12065 -0.3048)
			(end -0.67945 -0.3048)
			(stroke
				(width 0.1)
				(type default)
			)
			(layer "B.Fab")
		)
		(fp_line
			(start -0.67945 0.3048)
			(end -0.120396 0.3048)
			(stroke
				(width 0.1)
				(type default)
			)
			(layer "B.Fab")
		)
		(fp_line
			(start -0.67945 -0.3048)
			(end -0.67945 0.3048)
			(stroke
				(width 0.1)
				(type default)
			)
			(layer "B.Fab")
		)
		(pad "1" smd circle
			(at 0.40005 0)
			(size 0 0)
			(layers "B.Cu" "B.Mask" "B.Paste")
			(net "FM_BMC_CPU_FBRK_OUT_N")
		)
		(pad "2" smd circle
			(at -0.40005 0)
			(size 0 0)
			(layers "B.Cu" "B.Mask" "B.Paste")
			(net "FM_BMC_CPU_FBRK_OUT_R_N")
		)
	)
	(footprint ""
		(layer "B.Cu")
		(at 52.2986 -25.273)
		(property "Reference" ""
			(at 0 0 0)
			(layer "B.SilkS")
			(hide yes)
			(effects
				(font
					(size 1.27 1.27)
				)
				(justify mirror)
			)
		)
		(property "Value" ""
			(at 0 0 0)
			(layer "B.Fab")
			(effects
				(font
					(size 1.27 1.27)
				)
				(justify mirror)
			)
		)
		(duplicate_pad_numbers_are_jumpers no)
		(pad "1" smd circle
			(at 0 0 180)
			(size 0.9906 0.9906)
			(layers "B.Cu" "B.Mask" "B.Paste")
			(net "Net_159")
		)
		(zone
			(layer "B.Cu")
			(hatch none 0.5)
			(connect_pads
				(clearance 0)
			)
			(min_thickness 0.25)
			(keepout
				(tracks not_allowed)
				(vias allowed)
				(pads allowed)
				(copperpour not_allowed)
				(footprints allowed)
			)
			(placement
				(enabled no)
				(sheetname "")
			)
			(fill
				(thermal_gap 0.5)
				(thermal_bridge_width 0.5)
				(island_removal_mode 0)
			)
			(polygon
				(pts
					(arc
						(start 53.9242 -25.273)
						(mid 50.673 -25.273)
						(end 53.9242 -25.273)
					)
				)
			)
		)
	)
)
